(kicad_pcb
	(version 20260206)
	(generator "pcbnew")
	(generator_version "10.0")
	(general
		(thickness 1.6)
		(legacy_teardrops no)
	)
	(paper "A4")
	(title_block
		(title "03242023_DA0F0TMBIJ0_F0T_Motherboard_J_brd_V01_OCP.brd")
		(comment 1 "Grand Teton / footprints 5452-5458 of 6105")
	)
	(layers
		(0 "F.Cu" signal "TOP")
		(4 "In1.Cu" signal "GND")
		(6 "In2.Cu" signal "IN1")
		(8 "In3.Cu" signal "GND1")
		(10 "In4.Cu" signal "IN2")
		(12 "In5.Cu" signal "GND2")
		(14 "In6.Cu" signal "IN3")
		(16 "In7.Cu" signal "GND3")
		(18 "In8.Cu" signal "VCC")
		(20 "In9.Cu" signal "VCC1")
		(22 "In10.Cu" signal "GND4")
		(24 "In11.Cu" signal "IN4")
		(26 "In12.Cu" signal "GND5")
		(28 "In13.Cu" signal "IN5")
		(30 "In14.Cu" signal "GND6")
		(32 "In15.Cu" signal "IN6")
		(34 "In16.Cu" signal "GND7")
		(2 "B.Cu" signal "BOTTOM")
		(9 "F.Adhes" user "F.Adhesive")
		(11 "B.Adhes" user "B.Adhesive")
		(13 "F.Paste" user "Package Geometry/Pastemask Top")
		(15 "B.Paste" user "Package Geometry/Pastemask Bottom")
		(5 "F.SilkS" user "Ref Des/Silkscreen Top")
		(7 "B.SilkS" user "Ref Des/Silkscreen Bottom")
		(1 "F.Mask" user "Board Geometry/Soldermask Top")
		(3 "B.Mask" user "Board Geometry/Soldermask Bottom")
		(17 "Dwgs.User" user "User.Drawings")
		(19 "Cmts.User" user "User.Comments")
		(21 "Eco1.User" user "User.Eco1")
		(23 "Eco2.User" user "User.Eco2")
		(25 "Edge.Cuts" user "Board Geometry/Outline")
		(27 "Margin" user)
		(31 "F.CrtYd" user "Package Geometry/Place Bound Top")
		(29 "B.CrtYd" user "Package Geometry/Place Bound Bottom")
		(35 "F.Fab" user "Ref Des/Assembly Top")
		(33 "B.Fab" user "Ref Des/Assembly Bottom")
	)
	(footprint ""
		(layer "B.Cu")
		(at 359.43032 -358.522016)
		(property "Reference" "PR451"
			(at 0 0 0)
			(layer "B.SilkS")
			(hide yes)
			(effects
				(font
					(size 1.27 1.27)
				)
				(justify mirror)
			)
		)
		(property "Value" ""
			(at 0 0 0)
			(layer "B.Fab")
			(effects
				(font
					(size 1.27 1.27)
				)
				(justify mirror)
			)
		)
		(duplicate_pad_numbers_are_jumpers no)
		(fp_line
			(start -0.7874 -0.4064)
			(end -0.7874 0.4064)
			(stroke
				(width 0.1524)
				(type default)
			)
			(layer "B.SilkS")
		)
		(fp_line
			(start -0.7874 0.4064)
			(end 0.7874 0.4064)
			(stroke
				(width 0.1524)
				(type default)
			)
			(layer "B.SilkS")
		)
		(fp_line
			(start 0.7874 -0.4064)
			(end -0.7874 -0.4064)
			(stroke
				(width 0.1524)
				(type default)
			)
			(layer "B.SilkS")
		)
		(fp_line
			(start 0.7874 0.4064)
			(end 0.7874 -0.4064)
			(stroke
				(width 0.1524)
				(type default)
			)
			(layer "B.SilkS")
		)
		(fp_line
			(start -0.67945 -0.3048)
			(end -0.67945 0.3048)
			(stroke
				(width 0.1)
				(type default)
			)
			(layer "B.Fab")
		)
		(fp_line
			(start -0.67945 0.3048)
			(end -0.120396 0.3048)
			(stroke
				(width 0.1)
				(type default)
			)
			(layer "B.Fab")
		)
		(fp_line
			(start -0.12065 -0.3048)
			(end -0.67945 -0.3048)
			(stroke
				(width 0.1)
				(type default)
			)
			(layer "B.Fab")
		)
		(fp_line
			(start -0.12065 -0.2794)
			(end -0.12065 -0.3048)
			(stroke
				(width 0.1)
				(type default)
			)
			(layer "B.Fab")
		)
		(fp_line
			(start -0.120396 0.2794)
			(end 0.12065 0.2794)
			(stroke
				(width 0.1)
				(type default)
			)
			(layer "B.Fab")
		)
		(fp_line
			(start -0.120396 0.3048)
			(end -0.120396 0.2794)
			(stroke
				(width 0.1)
				(type default)
			)
			(layer "B.Fab")
		)
		(fp_line
			(start 0.12065 -0.305054)
			(end 0.12065 -0.2794)
			(stroke
				(width 0.1)
				(type default)
			)
			(layer "B.Fab")
		)
		(fp_line
			(start 0.12065 -0.2794)
			(end -0.12065 -0.2794)
			(stroke
				(width 0.1)
				(type default)
			)
			(layer "B.Fab")
		)
		(fp_line
			(start 0.12065 0.2794)
			(end 0.12065 0.3048)
			(stroke
				(width 0.1)
				(type default)
			)
			(layer "B.Fab")
		)
		(fp_line
			(start 0.12065 0.3048)
			(end 0.67945 0.3048)
			(stroke
				(width 0.1)
				(type default)
			)
			(layer "B.Fab")
		)
		(fp_line
			(start 0.67945 -0.305054)
			(end 0.12065 -0.305054)
			(stroke
				(width 0.1)
				(type default)
			)
			(layer "B.Fab")
		)
		(fp_line
			(start 0.67945 0.3048)
			(end 0.67945 -0.305054)
			(stroke
				(width 0.1)
				(type default)
			)
			(layer "B.Fab")
		)
		(pad "1" smd circle
			(at 0.40005 0 180)
			(size 0 0)
			(layers "B.Cu" "B.Mask" "B.Paste")
			(net "PVCCFA_EHV_FIVRA_CPU0_BTSEN")
		)
		(pad "2" smd circle
			(at -0.40005 0 180)
			(size 0 0)
			(layers "B.Cu" "B.Mask" "B.Paste")
			(net "GND")
		)
	)
	(footprint ""
		(layer "B.Cu")
		(at 179.758848 -406.903682)
		(property "Reference" "R1117"
			(at 0 0 0)
			(layer "B.SilkS")
			(hide yes)
			(effects
				(font
					(size 1.27 1.27)
				)
				(justify mirror)
			)
		)
		(property "Value" ""
			(at 0 0 0)
			(layer "B.Fab")
			(effects
				(font
					(size 1.27 1.27)
				)
				(justify mirror)
			)
		)
		(duplicate_pad_numbers_are_jumpers no)
		(fp_line
			(start -0.7874 -0.4064)
			(end -0.7874 0.4064)
			(stroke
				(width 0.1524)
				(type default)
			)
			(layer "B.SilkS")
		)
		(fp_line
			(start -0.7874 0.4064)
			(end 0.7874 0.4064)
			(stroke
				(width 0.1524)
				(type default)
			)
			(layer "B.SilkS")
		)
		(fp_line
			(start 0.7874 -0.4064)
			(end -0.7874 -0.4064)
			(stroke
				(width 0.1524)
				(type default)
			)
			(layer "B.SilkS")
		)
		(fp_line
			(start 0.7874 0.4064)
			(end 0.7874 -0.4064)
			(stroke
				(width 0.1524)
				(type default)
			)
			(layer "B.SilkS")
		)
		(fp_line
			(start -0.67945 -0.3048)
			(end -0.67945 0.3048)
			(stroke
				(width 0.1)
				(type default)
			)
			(layer "B.Fab")
		)
		(fp_line
			(start -0.67945 0.3048)
			(end -0.120396 0.3048)
			(stroke
				(width 0.1)
				(type default)
			)
			(layer "B.Fab")
		)
		(fp_line
			(start -0.12065 -0.3048)
			(end -0.67945 -0.3048)
			(stroke
				(width 0.1)
				(type default)
			)
			(layer "B.Fab")
		)
		(fp_line
			(start -0.12065 -0.2794)
			(end -0.12065 -0.3048)
			(stroke
				(width 0.1)
				(type default)
			)
			(layer "B.Fab")
		)
		(fp_line
			(start -0.120396 0.2794)
			(end 0.12065 0.2794)
			(stroke
				(width 0.1)
				(type default)
			)
			(layer "B.Fab")
		)
		(fp_line
			(start -0.120396 0.3048)
			(end -0.120396 0.2794)
			(stroke
				(width 0.1)
				(type default)
			)
			(layer "B.Fab")
		)
		(fp_line
			(start 0.12065 -0.305054)
			(end 0.12065 -0.2794)
			(stroke
				(width 0.1)
				(type default)
			)
			(layer "B.Fab")
		)
		(fp_line
			(start 0.12065 -0.2794)
			(end -0.12065 -0.2794)
			(stroke
				(width 0.1)
				(type default)
			)
			(layer "B.Fab")
		)
		(fp_line
			(start 0.12065 0.2794)
			(end 0.12065 0.3048)
			(stroke
				(width 0.1)
				(type default)
			)
			(layer "B.Fab")
		)
		(fp_line
			(start 0.12065 0.3048)
			(end 0.67945 0.3048)
			(stroke
				(width 0.1)
				(type default)
			)
			(layer "B.Fab")
		)
		(fp_line
			(start 0.67945 -0.305054)
			(end 0.12065 -0.305054)
			(stroke
				(width 0.1)
				(type default)
			)
			(layer "B.Fab")
		)
		(fp_line
			(start 0.67945 0.3048)
			(end 0.67945 -0.305054)
			(stroke
				(width 0.1)
				(type default)
			)
			(layer "B.Fab")
		)
		(pad "1" smd circle
			(at 0.40005 0 180)
			(size 0 0)
			(layers "B.Cu" "B.Mask" "B.Paste")
			(net "MB0_P12V_STBY_PWRGD")
		)
		(pad "2" smd circle
			(at -0.40005 0 180)
			(size 0 0)
			(layers "B.Cu" "B.Mask" "B.Paste")
			(net "AGND_HSC")
		)
	)
	(footprint ""
		(layer "B.Cu")
		(at 261.694168 -103.101902)
		(property "Reference" "L14"
			(at 0 0 0)
			(layer "B.SilkS")
			(hide yes)
			(effects
				(font
					(size 1.27 1.27)
				)
				(justify mirror)
			)
		)
		(property "Value" ""
			(at 0 0 0)
			(layer "B.Fab")
			(effects
				(font
					(size 1.27 1.27)
				)
				(justify mirror)
			)
		)
		(duplicate_pad_numbers_are_jumpers no)
		(fp_line
			(start -1.63576 -0.8128)
			(end -1.63576 0.8128)
			(stroke
				(width 0.1524)
				(type default)
			)
			(layer "B.SilkS")
		)
		(fp_line
			(start -1.63576 0.8128)
			(end 1.63576 0.8128)
			(stroke
				(width 0.1524)
				(type default)
			)
			(layer "B.SilkS")
		)
		(fp_line
			(start 1.63576 -0.8128)
			(end -1.63576 -0.8128)
			(stroke
				(width 0.1524)
				(type default)
			)
			(layer "B.SilkS")
		)
		(fp_line
			(start 1.63576 -0.8128)
			(end 1.63576 0.8128)
			(stroke
				(width 0.1524)
				(type default)
			)
			(layer "B.SilkS")
		)
		(fp_line
			(start -1.560576 -0.738632)
			(end 1.56083 -0.738632)
			(stroke
				(width 0.1)
				(type default)
			)
			(layer "B.Fab")
		)
		(fp_line
			(start -1.560576 0.7366)
			(end -1.560576 -0.738632)
			(stroke
				(width 0.1)
				(type default)
			)
			(layer "B.Fab")
		)
		(fp_line
			(start -1.524 0.7366)
			(end -1.560576 0.7366)
			(stroke
				(width 0.1)
				(type default)
			)
			(layer "B.Fab")
		)
		(fp_line
			(start 1.524 0.7366)
			(end -1.524 0.7366)
			(stroke
				(width 0.1)
				(type default)
			)
			(layer "B.Fab")
		)
		(fp_line
			(start 1.56083 -0.738632)
			(end 1.56083 0.7366)
			(stroke
				(width 0.1)
				(type default)
			)
			(layer "B.Fab")
		)
		(fp_line
			(start 1.56083 0.7366)
			(end 1.524 0.7366)
			(stroke
				(width 0.1)
				(type default)
			)
			(layer "B.Fab")
		)
		(pad "1" smd rect
			(at 0.94996 0)
			(size 1.1176 1.3716)
			(layers "B.Cu" "B.Mask" "B.Paste")
			(net "P3V3_AUX")
		)
		(pad "2" smd rect
			(at -0.94996 0)
			(size 1.1176 1.3716)
			(layers "B.Cu" "B.Mask" "B.Paste")
			(net "P3V3_AUX_CLK_GEN_VDDMXCK_CK440")
		)
	)
	(footprint ""
		(layer "B.Cu")
		(at 105.11536 -417.399216 180)
		(property "Reference" "L19"
			(at 0 0 0)
			(layer "B.SilkS")
			(hide yes)
			(effects
				(font
					(size 1.27 1.27)
				)
				(justify mirror)
			)
		)
		(property "Value" ""
			(at 0 0 0)
			(layer "B.Fab")
			(effects
				(font
					(size 1.27 1.27)
				)
				(justify mirror)
			)
		)
		(duplicate_pad_numbers_are_jumpers no)
		(fp_line
			(start 1.63576 -0.8128)
			(end 1.63576 0.8128)
			(stroke
				(width 0.1524)
				(type default)
			)
			(layer "B.SilkS")
		)
		(fp_line
			(start 1.63576 -0.8128)
			(end -1.63576 -0.8128)
			(stroke
				(width 0.1524)
				(type default)
			)
			(layer "B.SilkS")
		)
		(fp_line
			(start -1.63576 0.8128)
			(end 1.63576 0.8128)
			(stroke
				(width 0.1524)
				(type default)
			)
			(layer "B.SilkS")
		)
		(fp_line
			(start -1.63576 -0.8128)
			(end -1.63576 0.8128)
			(stroke
				(width 0.1524)
				(type default)
			)
			(layer "B.SilkS")
		)
		(fp_line
			(start 1.56083 0.7366)
			(end 1.524 0.7366)
			(stroke
				(width 0.1)
				(type default)
			)
			(layer "B.Fab")
		)
		(fp_line
			(start 1.56083 -0.738632)
			(end 1.56083 0.7366)
			(stroke
				(width 0.1)
				(type default)
			)
			(layer "B.Fab")
		)
		(fp_line
			(start 1.524 0.7366)
			(end -1.524 0.7366)
			(stroke
				(width 0.1)
				(type default)
			)
			(layer "B.Fab")
		)
		(fp_line
			(start -1.524 0.7366)
			(end -1.560576 0.7366)
			(stroke
				(width 0.1)
				(type default)
			)
			(layer "B.Fab")
		)
		(fp_line
			(start -1.560576 0.7366)
			(end -1.560576 -0.738632)
			(stroke
				(width 0.1)
				(type default)
			)
			(layer "B.Fab")
		)
		(fp_line
			(start -1.560576 -0.738632)
			(end 1.56083 -0.738632)
			(stroke
				(width 0.1)
				(type default)
			)
			(layer "B.Fab")
		)
		(pad "1" smd rect
			(at 0.94996 0 180)
			(size 1.1176 1.3716)
			(layers "B.Cu" "B.Mask" "B.Paste")
			(net "P3V3")
		)
		(pad "2" smd rect
			(at -0.94996 0 180)
			(size 1.1176 1.3716)
			(layers "B.Cu" "B.Mask" "B.Paste")
			(net "P3V3_9ZXL045")
		)
	)
	(footprint ""
		(layer "B.Cu")
		(at 350.158812 -337.853782)
		(property "Reference" "PR154"
			(at 0 0 0)
			(layer "B.SilkS")
			(hide yes)
			(effects
				(font
					(size 1.27 1.27)
				)
				(justify mirror)
			)
		)
		(property "Value" ""
			(at 0 0 0)
			(layer "B.Fab")
			(effects
				(font
					(size 1.27 1.27)
				)
				(justify mirror)
			)
		)
		(duplicate_pad_numbers_are_jumpers no)
		(fp_line
			(start -0.7874 -0.4064)
			(end -0.7874 0.4064)
			(stroke
				(width 0.1524)
				(type default)
			)
			(layer "B.SilkS")
		)
		(fp_line
			(start -0.7874 0.4064)
			(end 0.7874 0.4064)
			(stroke
				(width 0.1524)
				(type default)
			)
			(layer "B.SilkS")
		)
		(fp_line
			(start 0.7874 -0.4064)
			(end -0.7874 -0.4064)
			(stroke
				(width 0.1524)
				(type default)
			)
			(layer "B.SilkS")
		)
		(fp_line
			(start 0.7874 0.4064)
			(end 0.7874 -0.4064)
			(stroke
				(width 0.1524)
				(type default)
			)
			(layer "B.SilkS")
		)
		(fp_line
			(start -0.67945 -0.3048)
			(end -0.67945 0.3048)
			(stroke
				(width 0.1)
				(type default)
			)
			(layer "B.Fab")
		)
		(fp_line
			(start -0.67945 0.3048)
			(end -0.120396 0.3048)
			(stroke
				(width 0.1)
				(type default)
			)
			(layer "B.Fab")
		)
		(fp_line
			(start -0.12065 -0.3048)
			(end -0.67945 -0.3048)
			(stroke
				(width 0.1)
				(type default)
			)
			(layer "B.Fab")
		)
		(fp_line
			(start -0.12065 -0.2794)
			(end -0.12065 -0.3048)
			(stroke
				(width 0.1)
				(type default)
			)
			(layer "B.Fab")
		)
		(fp_line
			(start -0.120396 0.2794)
			(end 0.12065 0.2794)
			(stroke
				(width 0.1)
				(type default)
			)
			(layer "B.Fab")
		)
		(fp_line
			(start -0.120396 0.3048)
			(end -0.120396 0.2794)
			(stroke
				(width 0.1)
				(type default)
			)
			(layer "B.Fab")
		)
		(fp_line
			(start 0.12065 -0.305054)
			(end 0.12065 -0.2794)
			(stroke
				(width 0.1)
				(type default)
			)
			(layer "B.Fab")
		)
		(fp_line
			(start 0.12065 -0.2794)
			(end -0.12065 -0.2794)
			(stroke
				(width 0.1)
				(type default)
			)
			(layer "B.Fab")
		)
		(fp_line
			(start 0.12065 0.2794)
			(end 0.12065 0.3048)
			(stroke
				(width 0.1)
				(type default)
			)
			(layer "B.Fab")
		)
		(fp_line
			(start 0.12065 0.3048)
			(end 0.67945 0.3048)
			(stroke
				(width 0.1)
				(type default)
			)
			(layer "B.Fab")
		)
		(fp_line
			(start 0.67945 -0.305054)
			(end 0.12065 -0.305054)
			(stroke
				(width 0.1)
				(type default)
			)
			(layer "B.Fab")
		)
		(fp_line
			(start 0.67945 0.3048)
			(end 0.67945 -0.305054)
			(stroke
				(width 0.1)
				(type default)
			)
			(layer "B.Fab")
		)
		(pad "1" smd circle
			(at 0.40005 0 180)
			(size 0 0)
			(layers "B.Cu" "B.Mask" "B.Paste")
			(net "PVCCIN_CPU0_VOS2")
		)
		(pad "2" smd circle
			(at -0.40005 0 180)
			(size 0 0)
			(layers "B.Cu" "B.Mask" "B.Paste")
			(net "PVCCIN_CPU0")
		)
	)
	(footprint ""
		(layer "B.Cu")
		(at 449.526914 -8.344916 -90)
		(property "Reference" "R415"
			(at 0 0 90)
			(layer "B.SilkS")
			(hide yes)
			(effects
				(font
					(size 1.27 1.27)
				)
				(justify mirror)
			)
		)
		(property "Value" ""
			(at 0 0 90)
			(layer "B.Fab")
			(effects
				(font
					(size 1.27 1.27)
				)
				(justify mirror)
			)
		)
		(duplicate_pad_numbers_are_jumpers no)
		(fp_line
			(start -0.7874 0.4064)
			(end 0.7874 0.4064)
			(stroke
				(width 0.1524)
				(type default)
			)
			(layer "B.SilkS")
		)
		(fp_line
			(start 0.7874 0.4064)
			(end 0.7874 -0.4064)
			(stroke
				(width 0.1524)
				(type default)
			)
			(layer "B.SilkS")
		)
		(fp_line
			(start -0.7874 -0.4064)
			(end -0.7874 0.4064)
			(stroke
				(width 0.1524)
				(type default)
			)
			(layer "B.SilkS")
		)
		(fp_line
			(start 0.7874 -0.4064)
			(end -0.7874 -0.4064)
			(stroke
				(width 0.1524)
				(type default)
			)
			(layer "B.SilkS")
		)
		(fp_line
			(start -0.67945 0.3048)
			(end -0.120396 0.3048)
			(stroke
				(width 0.1)
				(type default)
			)
			(layer "B.Fab")
		)
		(fp_line
			(start -0.120396 0.3048)
			(end -0.120396 0.2794)
			(stroke
				(width 0.1)
				(type default)
			)
			(layer "B.Fab")
		)
		(fp_line
			(start 0.12065 0.3048)
			(end 0.67945 0.3048)
			(stroke
				(width 0.1)
				(type default)
			)
			(layer "B.Fab")
		)
		(fp_line
			(start 0.67945 0.3048)
			(end 0.67945 -0.305054)
			(stroke
				(width 0.1)
				(type default)
			)
			(layer "B.Fab")
		)
		(fp_line
			(start -0.120396 0.2794)
			(end 0.12065 0.2794)
			(stroke
				(width 0.1)
				(type default)
			)
			(layer "B.Fab")
		)
		(fp_line
			(start 0.12065 0.2794)
			(end 0.12065 0.3048)
			(stroke
				(width 0.1)
				(type default)
			)
			(layer "B.Fab")
		)
		(fp_line
			(start -0.12065 -0.2794)
			(end -0.12065 -0.3048)
			(stroke
				(width 0.1)
				(type default)
			)
			(layer "B.Fab")
		)
		(fp_line
			(start 0.12065 -0.2794)
			(end -0.12065 -0.2794)
			(stroke
				(width 0.1)
				(type default)
			)
			(layer "B.Fab")
		)
		(fp_line
			(start -0.67945 -0.3048)
			(end -0.67945 0.3048)
			(stroke
				(width 0.1)
				(type default)
			)
			(layer "B.Fab")
		)
		(fp_line
			(start -0.12065 -0.3048)
			(end -0.67945 -0.3048)
			(stroke
				(width 0.1)
				(type default)
			)
			(layer "B.Fab")
		)
		(fp_line
			(start 0.12065 -0.305054)
			(end 0.12065 -0.2794)
			(stroke
				(width 0.1)
				(type default)
			)
			(layer "B.Fab")
		)
		(fp_line
			(start 0.67945 -0.305054)
			(end 0.12065 -0.305054)
			(stroke
				(width 0.1)
				(type default)
			)
			(layer "B.Fab")
		)
		(pad "1" smd circle
			(at 0.40005 0 90)
			(size 0 0)
			(layers "B.Cu" "B.Mask" "B.Paste")
			(net "OCP_SFF_ID1")
		)
		(pad "2" smd circle
			(at -0.40005 0 90)
			(size 0 0)
			(layers "B.Cu" "B.Mask" "B.Paste")
			(net "GND")
		)
	)
	(footprint ""
		(layer "B.Cu")
		(at 113.677954 -326.99706 -90)
		(property "Reference" "PC1990"
			(at 0 0 90)
			(layer "B.SilkS")
			(hide yes)
			(effects
				(font
					(size 1.27 1.27)
				)
				(justify mirror)
			)
		)
		(property "Value" ""
			(at 0 0 90)
			(layer "B.Fab")
			(effects
				(font
					(size 1.27 1.27)
				)
				(justify mirror)
			)
		)
		(duplicate_pad_numbers_are_jumpers no)
		(fp_line
			(start -4.533392 2.249932)
			(end 4.533392 2.249932)
			(stroke
				(width 0.1524)
				(type default)
			)
			(layer "B.SilkS")
		)
		(fp_line
			(start 4.533392 2.249932)
			(end 4.533392 -2.249932)
			(stroke
				(width 0.1524)
				(type default)
			)
			(layer "B.SilkS")
		)
		(fp_line
			(start -4.533392 -2.249932)
			(end -4.533392 2.249932)
			(stroke
				(width 0.1524)
				(type default)
			)
			(layer "B.SilkS")
		)
		(fp_line
			(start 4.533392 -2.249932)
			(end -4.533392 -2.249932)
			(stroke
				(width 0.1524)
				(type default)
			)
			(layer "B.SilkS")
		)
		(fp_rect
			(start 5.39242 2.326132)
			(end 4.533392 -2.326132)
			(stroke
				(width 0)
				(type default)
			)
			(fill yes)
			(layer "B.SilkS")
		)
		(fp_line
			(start -3.750056 2.249932)
			(end 3.750056 2.249932)
			(stroke
				(width 0.1)
				(type default)
			)
			(layer "B.Fab")
		)
		(fp_line
			(start 3.750056 2.249932)
			(end 3.750056 -2.249932)
			(stroke
				(width 0.1)
				(type default)
			)
			(layer "B.Fab")
		)
		(fp_line
			(start -3.750056 -2.249932)
			(end -3.750056 2.249932)
			(stroke
				(width 0.1)
				(type default)
			)
			(layer "B.Fab")
		)
		(fp_line
			(start 3.750056 -2.249932)
			(end -3.750056 -2.249932)
			(stroke
				(width 0.1)
				(type default)
			)
			(layer "B.Fab")
		)
		(fp_text user "-"
			(at -4.719828 1.309624 270)
			(unlocked yes)
			(layer "B.SilkS")
			(effects
				(font
					(size 1.905 1.4224)
					(thickness 0.1524)
				)
				(justify left mirror)
			)
		)
		(fp_text user "+"
			(at 6.322314 0.786384 180)
			(unlocked yes)
			(layer "B.SilkS")
			(effects
				(font
					(size 1.905 1.4224)
					(thickness 0.1524)
				)
				(justify left mirror)
			)
		)
		(fp_text user "+"
			(at 6.322314 0.786384 180)
			(unlocked yes)
			(layer "B.Fab")
			(effects
				(font
					(size 1.905 1.4224)
					(thickness 0.1524)
				)
				(justify left mirror)
			)
		)
		(fp_text user "-"
			(at -4.8514 -0.14605 270)
			(unlocked yes)
			(layer "B.Fab")
			(effects
				(font
					(size 1.905 1.4224)
					(thickness 0.1524)
				)
				(justify left mirror)
			)
		)
		(pad "1" smd rect
			(at 3.199892 0 90)
			(size 2.413 2.8194)
			(layers "B.Cu" "B.Mask" "B.Paste")
			(net "PVCCIN_CPU1")
		)
		(pad "2" smd rect
			(at -3.199892 0 90)
			(size 2.413 2.8194)
			(layers "B.Cu" "B.Mask" "B.Paste")
			(net "GND")
		)
	)
)
